FILE_TYPE=LIBRARY_PARTS;
primitive 'IR3889MTRPBF';
  pin
    'NC3':
      PIN_NUMBER='(34)';
      OUTPUT_TYPE='(TS,TS)';
      INPUT_LOAD='(-0.01,0.01)';
      OUTPUT_LOAD='(1.0,-1.0)';
    'TON||MODE':
      PIN_NUMBER='(36)';
      INPUT_LOAD='(-0.01,0.01)';
    'VIN':
      PIN_NUMBER='(3)';
      PINUSE='POWER';
      NO_LOAD_CHECK='Both';
      NO_IO_CHECK='Both';
      NO_ASSERT_CHECK='TRUE';
      NO_DIR_CHECK='TRUE';
      ALLOW_CONNECT='TRUE';
    'FB':
      PIN_NUMBER='(30)';
      INPUT_LOAD='(-0.01,0.01)';
    'BOOT':
      PIN_NUMBER='(26)';
      INPUT_LOAD='(-0.01,0.01)';
    'ILIM':
      PIN_NUMBER='(1)';
      INPUT_LOAD='(-0.01,0.01)';
    'PHASE':
      PIN_NUMBER='(25)';
      OUTPUT_LOAD='(1.0,-1.0)';
    'VCC||LDO':
      PIN_NUMBER='(4)';
      PINUSE='POWER';
      NO_LOAD_CHECK='Both';
      NO_IO_CHECK='Both';
      NO_ASSERT_CHECK='TRUE';
      NO_DIR_CHECK='TRUE';
      ALLOW_CONNECT='TRUE';
    'VSENM':
      PIN_NUMBER='(31)';
      INPUT_LOAD='(-0.01,0.01)';
    'NC4':
      PIN_NUMBER='(35)';
      OUTPUT_TYPE='(TS,TS)';
      INPUT_LOAD='(-0.01,0.01)';
      OUTPUT_LOAD='(1.0,-1.0)';
    'PGND':
      PIN_NUMBER='(7_10-19)';
      PINUSE='POWER';
      NO_LOAD_CHECK='Both';
      NO_IO_CHECK='Both';
      NO_ASSERT_CHECK='TRUE';
      NO_DIR_CHECK='TRUE';
      ALLOW_CONNECT='TRUE';
    'NC2':
      PIN_NUMBER='(33)';
      OUTPUT_TYPE='(TS,TS)';
      INPUT_LOAD='(-0.01,0.01)';
      OUTPUT_LOAD='(1.0,-1.0)';
    'SW':
      PIN_NUMBER='(11_18)';
      PINUSE='POWER';
      NO_LOAD_CHECK='Both';
      NO_IO_CHECK='Both';
      NO_ASSERT_CHECK='TRUE';
      NO_DIR_CHECK='TRUE';
      ALLOW_CONNECT='TRUE';
    'PVIN':
      PIN_NUMBER='(20_24)';
      PINUSE='POWER';
      NO_LOAD_CHECK='Both';
      NO_IO_CHECK='Both';
      NO_ASSERT_CHECK='TRUE';
      NO_DIR_CHECK='TRUE';
      ALLOW_CONNECT='TRUE';
    'PGOOD':
      PIN_NUMBER='(2)';
      OUTPUT_LOAD='(1.0,-1.0)';
    'NC1':
      PIN_NUMBER='(28)';
      OUTPUT_TYPE='(TS,TS)';
      INPUT_LOAD='(-0.01,0.01)';
      OUTPUT_LOAD='(1.0,-1.0)';
    'AGND':
      PIN_NUMBER='(32)';
      PINUSE='POWER';
      NO_LOAD_CHECK='Both';
      NO_IO_CHECK='Both';
      NO_ASSERT_CHECK='TRUE';
      NO_DIR_CHECK='TRUE';
      ALLOW_CONNECT='TRUE';
    'EN':
      PIN_NUMBER='(27)';
      INPUT_LOAD='(-0.01,0.01)';
    'VDRV':
      PIN_NUMBER='(5)';
      PINUSE='POWER';
      NO_LOAD_CHECK='Both';
      NO_IO_CHECK='Both';
      NO_ASSERT_CHECK='TRUE';
      NO_DIR_CHECK='TRUE';
      ALLOW_CONNECT='TRUE';
    'GATEL1':
      PIN_NUMBER='(6)';
      INPUT_LOAD='(-0.01,0.01)';
    'SS||LATCH':
      PIN_NUMBER='(29)';
      INPUT_LOAD='(-0.01,0.01)';
    'GATEL2':
      PIN_NUMBER='(37)';
      INPUT_LOAD='(-0.01,0.01)';
  end_pin;
  body
    PART_NAME='IR3889MTRPBF';
    BODY_NAME='IR3889MTRPBF';
    PHYS_DES_PREFIX='U';
    CLASS='IC';
  end_body;
end_primitive;

END.
